# S9S_MB_2U (Grand Teton) — schematic netlist excerpt (pin names and nets, part order shuffled) for the footprints in the layout excerpt that follows; sources: Cadence DE-HDL packaged netlist, KiCad conversion of 03242023_DA0F0TMBIJ0_F0T_Motherboard_J_brd_V01_OCP.brd

R3458  Q_RES  1 1% CHIP  pkg 0603LF  page 217 : A = P3V3_AUX ; B = VCC_PLD_CORE
PR218  Q_RES  1K 1% EMPTY  pkg 0402LF  page 296 : A = PVCCD_HV_CPU1_ISENSE_N ; B = GND

(kicad_pcb
	(version 20260206)
	(generator "pcbnew")
	(generator_version "10.0")
	(general
		(thickness 1.6)
		(legacy_teardrops no)
	)
	(paper "A4")
	(title_block
		(title "03242023_DA0F0TMBIJ0_F0T_Motherboard_J_brd_V01_OCP.brd")
		(comment 1 "Grand Teton / footprints 5972-5973 of 6105")
	)
	(layers
		(0 "F.Cu" signal "TOP")
		(4 "In1.Cu" signal "GND")
		(6 "In2.Cu" signal "IN1")
		(8 "In3.Cu" signal "GND1")
		(10 "In4.Cu" signal "IN2")
		(12 "In5.Cu" signal "GND2")
		(14 "In6.Cu" signal "IN3")
		(16 "In7.Cu" signal "GND3")
		(18 "In8.Cu" signal "VCC")
		(20 "In9.Cu" signal "VCC1")
		(22 "In10.Cu" signal "GND4")
		(24 "In11.Cu" signal "IN4")
		(26 "In12.Cu" signal "GND5")
		(28 "In13.Cu" signal "IN5")
		(30 "In14.Cu" signal "GND6")
		(32 "In15.Cu" signal "IN6")
		(34 "In16.Cu" signal "GND7")
		(2 "B.Cu" signal "BOTTOM")
		(9 "F.Adhes" user "F.Adhesive")
		(11 "B.Adhes" user "B.Adhesive")
		(13 "F.Paste" user "Package Geometry/Pastemask Top")
		(15 "B.Paste" user "Package Geometry/Pastemask Bottom")
		(5 "F.SilkS" user "Ref Des/Silkscreen Top")
		(7 "B.SilkS" user "Ref Des/Silkscreen Bottom")
		(1 "F.Mask" user "Board Geometry/Soldermask Top")
		(3 "B.Mask" user "Board Geometry/Soldermask Bottom")
		(17 "Dwgs.User" user "User.Drawings")
		(19 "Cmts.User" user "User.Comments")
		(21 "Eco1.User" user "User.Eco1")
		(23 "Eco2.User" user "User.Eco2")
		(25 "Edge.Cuts" user "Board Geometry/Outline")
		(27 "Margin" user)
		(31 "F.CrtYd" user "Package Geometry/Place Bound Top")
		(29 "B.CrtYd" user "Package Geometry/Place Bound Bottom")
		(35 "F.Fab" user "Ref Des/Assembly Top")
		(33 "B.Fab" user "Ref Des/Assembly Bottom")
	)
	(footprint ""
		(layer "B.Cu")
		(at 29.577538 -167.0177)
		(property "Reference" "PR218"
			(at 0 0 0)
			(layer "B.SilkS")
			(hide yes)
			(effects
				(font
					(size 1.27 1.27)
				)
				(justify mirror)
			)
		)
		(property "Value" ""
			(at 0 0 0)
			(layer "B.Fab")
			(effects
				(font
					(size 1.27 1.27)
				)
				(justify mirror)
			)
		)
		(duplicate_pad_numbers_are_jumpers no)
		(fp_line
			(start -0.7874 -0.4064)
			(end -0.7874 0.4064)
			(stroke
				(width 0.1524)
				(type default)
			)
			(layer "B.SilkS")
		)
		(fp_line
			(start -0.7874 0.4064)
			(end 0.7874 0.4064)
			(stroke
				(width 0.1524)
				(type default)
			)
			(layer "B.SilkS")
		)
		(fp_line
			(start 0.7874 -0.4064)
			(end -0.7874 -0.4064)
			(stroke
				(width 0.1524)
				(type default)
			)
			(layer "B.SilkS")
		)
		(fp_line
			(start 0.7874 0.4064)
			(end 0.7874 -0.4064)
			(stroke
				(width 0.1524)
				(type default)
			)
			(layer "B.SilkS")
		)
		(fp_line
			(start -0.67945 -0.3048)
			(end -0.67945 0.3048)
			(stroke
				(width 0.1)
				(type default)
			)
			(layer "B.Fab")
		)
		(fp_line
			(start -0.67945 0.3048)
			(end -0.120396 0.3048)
			(stroke
				(width 0.1)
				(type default)
			)
			(layer "B.Fab")
		)
		(fp_line
			(start -0.12065 -0.3048)
			(end -0.67945 -0.3048)
			(stroke
				(width 0.1)
				(type default)
			)
			(layer "B.Fab")
		)
		(fp_line
			(start -0.12065 -0.2794)
			(end -0.12065 -0.3048)
			(stroke
				(width 0.1)
				(type default)
			)
			(layer "B.Fab")
		)
		(fp_line
			(start -0.120396 0.2794)
			(end 0.12065 0.2794)
			(stroke
				(width 0.1)
				(type default)
			)
			(layer "B.Fab")
		)
		(fp_line
			(start -0.120396 0.3048)
			(end -0.120396 0.2794)
			(stroke
				(width 0.1)
				(type default)
			)
			(layer "B.Fab")
		)
		(fp_line
			(start 0.12065 -0.305054)
			(end 0.12065 -0.2794)
			(stroke
				(width 0.1)
				(type default)
			)
			(layer "B.Fab")
		)
		(fp_line
			(start 0.12065 -0.2794)
			(end -0.12065 -0.2794)
			(stroke
				(width 0.1)
				(type default)
			)
			(layer "B.Fab")
		)
		(fp_line
			(start 0.12065 0.2794)
			(end 0.12065 0.3048)
			(stroke
				(width 0.1)
				(type default)
			)
			(layer "B.Fab")
		)
		(fp_line
			(start 0.12065 0.3048)
			(end 0.67945 0.3048)
			(stroke
				(width 0.1)
				(type default)
			)
			(layer "B.Fab")
		)
		(fp_line
			(start 0.67945 -0.305054)
			(end 0.12065 -0.305054)
			(stroke
				(width 0.1)
				(type default)
			)
			(layer "B.Fab")
		)
		(fp_line
			(start 0.67945 0.3048)
			(end 0.67945 -0.305054)
			(stroke
				(width 0.1)
				(type default)
			)
			(layer "B.Fab")
		)
		(pad "1" smd circle
			(at 0.40005 0 180)
			(size 0 0)
			(layers "B.Cu" "B.Mask" "B.Paste")
			(net "PVCCD_HV_CPU1_ISENSE_N")
		)
		(pad "2" smd circle
			(at -0.40005 0 180)
			(size 0 0)
			(layers "B.Cu" "B.Mask" "B.Paste")
			(net "GND")
		)
	)
	(footprint ""
		(layer "B.Cu")
		(at 179.63388 -125.313948)
		(property "Reference" "R3458"
			(at 0 0 0)
			(layer "B.SilkS")
			(hide yes)
			(effects
				(font
					(size 1.27 1.27)
				)
				(justify mirror)
			)
		)
		(property "Value" ""
			(at 0 0 0)
			(layer "B.Fab")
			(effects
				(font
					(size 1.27 1.27)
				)
				(justify mirror)
			)
		)
		(duplicate_pad_numbers_are_jumpers no)
		(fp_line
			(start -1.2954 -0.5842)
			(end -1.2954 0.5842)
			(stroke
				(width 0.1524)
				(type default)
			)
			(layer "B.SilkS")
		)
		(fp_line
			(start -1.2954 0.5842)
			(end 1.2954 0.5842)
			(stroke
				(width 0.1524)
				(type default)
			)
			(layer "B.SilkS")
		)
		(fp_line
			(start 1.2954 -0.5842)
			(end -1.2954 -0.5842)
			(stroke
				(width 0.1524)
				(type default)
			)
			(layer "B.SilkS")
		)
		(fp_line
			(start 1.2954 0.5842)
			(end 1.2954 -0.5842)
			(stroke
				(width 0.1524)
				(type default)
			)
			(layer "B.SilkS")
		)
		(fp_line
			(start -1.1938 -0.406654)
			(end -1.1938 0.4064)
			(stroke
				(width 0.1)
				(type default)
			)
			(layer "B.Fab")
		)
		(fp_line
			(start -1.1938 0.4064)
			(end -0.8636 0.4064)
			(stroke
				(width 0.1)
				(type default)
			)
			(layer "B.Fab")
		)
		(fp_line
			(start -0.8636 -0.4572)
			(end -0.8636 -0.406654)
			(stroke
				(width 0.1)
				(type default)
			)
			(layer "B.Fab")
		)
		(fp_line
			(start -0.8636 -0.406654)
			(end -1.1938 -0.406654)
			(stroke
				(width 0.1)
				(type default)
			)
			(layer "B.Fab")
		)
		(fp_line
			(start -0.8636 0.4064)
			(end -0.8636 0.4572)
			(stroke
				(width 0.1)
				(type default)
			)
			(layer "B.Fab")
		)
		(fp_line
			(start -0.8636 0.4572)
			(end 0.8636 0.4572)
			(stroke
				(width 0.1)
				(type default)
			)
			(layer "B.Fab")
		)
		(fp_line
			(start 0.8636 -0.4572)
			(end -0.8636 -0.4572)
			(stroke
				(width 0.1)
				(type default)
			)
			(layer "B.Fab")
		)
		(fp_line
			(start 0.8636 -0.406654)
			(end 0.8636 -0.4572)
			(stroke
				(width 0.1)
				(type default)
			)
			(layer "B.Fab")
		)
		(fp_line
			(start 0.8636 0.4064)
			(end 1.1938 0.4064)
			(stroke
				(width 0.1)
				(type default)
			)
			(layer "B.Fab")
		)
		(fp_line
			(start 0.8636 0.4318)
			(end 0.8636 0.4064)
			(stroke
				(width 0.1)
				(type default)
			)
			(layer "B.Fab")
		)
		(fp_line
			(start 0.8636 0.4572)
			(end 0.8636 0.4318)
			(stroke
				(width 0.1)
				(type default)
			)
			(layer "B.Fab")
		)
		(fp_line
			(start 1.1938 -0.406654)
			(end 0.8636 -0.406654)
			(stroke
				(width 0.1)
				(type default)
			)
			(layer "B.Fab")
		)
		(fp_line
			(start 1.1938 0.4064)
			(end 1.1938 -0.406654)
			(stroke
				(width 0.1)
				(type default)
			)
			(layer "B.Fab")
		)
		(pad "1" smd rect
			(at 0.7366 0 270)
			(size 0.7112 0.8128)
			(layers "B.Cu" "B.Mask" "B.Paste")
			(net "P3V3_AUX")
		)
		(pad "2" smd rect
			(at -0.7366 0 270)
			(size 0.7112 0.8128)
			(layers "B.Cu" "B.Mask" "B.Paste")
			(net "VCC_PLD_CORE")
		)
	)
)
